(kicad_pcb
	(version 20260206)
	(generator "pcbnew")
	(generator_version "10.0")
	(general
		(thickness 1.6)
		(legacy_teardrops no)
	)
	(paper "A4")
	(title_block
		(title "12092022_DA0F0TFB6D0_F0T_FAN_BOARD_MP5048_D_brd_v02_OCP.brd")
		(comment 1 "Grand Teton / footprints 603-608 of 924")
	)
	(layers
		(0 "F.Cu" signal "TOP")
		(4 "In1.Cu" signal "GND")
		(6 "In2.Cu" signal "IN1")
		(8 "In3.Cu" signal "IN2")
		(10 "In4.Cu" signal "GND1")
		(2 "B.Cu" signal "BOTTOM")
		(9 "F.Adhes" user "F.Adhesive")
		(11 "B.Adhes" user "B.Adhesive")
		(13 "F.Paste" user "Package Geometry/Pastemask Top")
		(15 "B.Paste" user "Package Geometry/Pastemask Bottom")
		(5 "F.SilkS" user "Ref Des/Silkscreen Top")
		(7 "B.SilkS" user "Ref Des/Silkscreen Bottom")
		(1 "F.Mask" user "Board Geometry/Soldermask Top")
		(3 "B.Mask" user "Board Geometry/Soldermask Bottom")
		(17 "Dwgs.User" user "User.Drawings")
		(19 "Cmts.User" user "User.Comments")
		(21 "Eco1.User" user "User.Eco1")
		(23 "Eco2.User" user "User.Eco2")
		(25 "Edge.Cuts" user "Board Geometry/Outline")
		(27 "Margin" user)
		(31 "F.CrtYd" user "Package Geometry/Place Bound Top")
		(29 "B.CrtYd" user "Package Geometry/Place Bound Bottom")
		(35 "F.Fab" user "Ref Des/Assembly Top")
		(33 "B.Fab" user "Ref Des/Assembly Bottom")
	)
	(footprint ""
		(layer "F.Cu")
		(at 15.24 -120.65 180)
		(property "Reference" "R5315"
			(at 0 0 180)
			(layer "F.SilkS")
			(hide yes)
			(effects
				(font
					(size 1.27 1.27)
				)
			)
		)
		(property "Value" ""
			(at 0 0 180)
			(layer "F.Fab")
			(effects
				(font
					(size 1.27 1.27)
				)
			)
		)
		(duplicate_pad_numbers_are_jumpers no)
		(fp_line
			(start 0.7874 0.4064)
			(end -0.7874 0.4064)
			(stroke
				(width 0.1524)
				(type default)
			)
			(layer "F.SilkS")
		)
		(fp_line
			(start 0.7874 -0.4064)
			(end 0.7874 0.4064)
			(stroke
				(width 0.1524)
				(type default)
			)
			(layer "F.SilkS")
		)
		(fp_line
			(start -0.7874 0.4064)
			(end -0.7874 -0.4064)
			(stroke
				(width 0.1524)
				(type default)
			)
			(layer "F.SilkS")
		)
		(fp_line
			(start -0.7874 -0.4064)
			(end 0.7874 -0.4064)
			(stroke
				(width 0.1524)
				(type default)
			)
			(layer "F.SilkS")
		)
		(fp_line
			(start 0.67945 0.3048)
			(end 0.120396 0.3048)
			(stroke
				(width 0.1)
				(type default)
			)
			(layer "F.Fab")
		)
		(fp_line
			(start 0.67945 -0.3048)
			(end 0.67945 0.3048)
			(stroke
				(width 0.1)
				(type default)
			)
			(layer "F.Fab")
		)
		(fp_line
			(start 0.12065 -0.2794)
			(end 0.12065 -0.3048)
			(stroke
				(width 0.1)
				(type default)
			)
			(layer "F.Fab")
		)
		(fp_line
			(start 0.12065 -0.3048)
			(end 0.67945 -0.3048)
			(stroke
				(width 0.1)
				(type default)
			)
			(layer "F.Fab")
		)
		(fp_line
			(start 0.120396 0.3048)
			(end 0.120396 0.2794)
			(stroke
				(width 0.1)
				(type default)
			)
			(layer "F.Fab")
		)
		(fp_line
			(start 0.120396 0.2794)
			(end -0.12065 0.2794)
			(stroke
				(width 0.1)
				(type default)
			)
			(layer "F.Fab")
		)
		(fp_line
			(start -0.12065 0.3048)
			(end -0.67945 0.3048)
			(stroke
				(width 0.1)
				(type default)
			)
			(layer "F.Fab")
		)
		(fp_line
			(start -0.12065 0.2794)
			(end -0.12065 0.3048)
			(stroke
				(width 0.1)
				(type default)
			)
			(layer "F.Fab")
		)
		(fp_line
			(start -0.12065 -0.2794)
			(end 0.12065 -0.2794)
			(stroke
				(width 0.1)
				(type default)
			)
			(layer "F.Fab")
		)
		(fp_line
			(start -0.12065 -0.305054)
			(end -0.12065 -0.2794)
			(stroke
				(width 0.1)
				(type default)
			)
			(layer "F.Fab")
		)
		(fp_line
			(start -0.67945 0.3048)
			(end -0.67945 -0.305054)
			(stroke
				(width 0.1)
				(type default)
			)
			(layer "F.Fab")
		)
		(fp_line
			(start -0.67945 -0.305054)
			(end -0.12065 -0.305054)
			(stroke
				(width 0.1)
				(type default)
			)
			(layer "F.Fab")
		)
		(pad "1" smd rect
			(at -0.40005 0)
			(size 0.4572 0.508)
			(layers "F.Cu" "F.Mask" "F.Paste")
			(net "FAN_5_TACH_OL_R")
		)
		(pad "2" smd rect
			(at 0.40005 0)
			(size 0.4572 0.508)
			(layers "F.Cu" "F.Mask" "F.Paste")
			(net "FAN_5_TACH_OL")
		)
	)
	(footprint ""
		(layer "F.Cu")
		(at 22.098 -114.427)
		(property "Reference" "R352"
			(at 0 0 0)
			(layer "F.SilkS")
			(hide yes)
			(effects
				(font
					(size 1.27 1.27)
				)
			)
		)
		(property "Value" ""
			(at 0 0 0)
			(layer "F.Fab")
			(effects
				(font
					(size 1.27 1.27)
				)
			)
		)
		(duplicate_pad_numbers_are_jumpers no)
		(fp_line
			(start -0.7874 -0.4064)
			(end 0.7874 -0.4064)
			(stroke
				(width 0.1524)
				(type default)
			)
			(layer "F.SilkS")
		)
		(fp_line
			(start -0.7874 0.4064)
			(end -0.7874 -0.4064)
			(stroke
				(width 0.1524)
				(type default)
			)
			(layer "F.SilkS")
		)
		(fp_line
			(start 0.7874 -0.4064)
			(end 0.7874 0.4064)
			(stroke
				(width 0.1524)
				(type default)
			)
			(layer "F.SilkS")
		)
		(fp_line
			(start 0.7874 0.4064)
			(end -0.7874 0.4064)
			(stroke
				(width 0.1524)
				(type default)
			)
			(layer "F.SilkS")
		)
		(fp_line
			(start -0.67945 -0.305054)
			(end -0.12065 -0.305054)
			(stroke
				(width 0.1)
				(type default)
			)
			(layer "F.Fab")
		)
		(fp_line
			(start -0.67945 0.3048)
			(end -0.67945 -0.305054)
			(stroke
				(width 0.1)
				(type default)
			)
			(layer "F.Fab")
		)
		(fp_line
			(start -0.12065 -0.305054)
			(end -0.12065 -0.2794)
			(stroke
				(width 0.1)
				(type default)
			)
			(layer "F.Fab")
		)
		(fp_line
			(start -0.12065 -0.2794)
			(end 0.12065 -0.2794)
			(stroke
				(width 0.1)
				(type default)
			)
			(layer "F.Fab")
		)
		(fp_line
			(start -0.12065 0.2794)
			(end -0.12065 0.3048)
			(stroke
				(width 0.1)
				(type default)
			)
			(layer "F.Fab")
		)
		(fp_line
			(start -0.12065 0.3048)
			(end -0.67945 0.3048)
			(stroke
				(width 0.1)
				(type default)
			)
			(layer "F.Fab")
		)
		(fp_line
			(start 0.120396 0.2794)
			(end -0.12065 0.2794)
			(stroke
				(width 0.1)
				(type default)
			)
			(layer "F.Fab")
		)
		(fp_line
			(start 0.120396 0.3048)
			(end 0.120396 0.2794)
			(stroke
				(width 0.1)
				(type default)
			)
			(layer "F.Fab")
		)
		(fp_line
			(start 0.12065 -0.3048)
			(end 0.67945 -0.3048)
			(stroke
				(width 0.1)
				(type default)
			)
			(layer "F.Fab")
		)
		(fp_line
			(start 0.12065 -0.2794)
			(end 0.12065 -0.3048)
			(stroke
				(width 0.1)
				(type default)
			)
			(layer "F.Fab")
		)
		(fp_line
			(start 0.67945 -0.3048)
			(end 0.67945 0.3048)
			(stroke
				(width 0.1)
				(type default)
			)
			(layer "F.Fab")
		)
		(fp_line
			(start 0.67945 0.3048)
			(end 0.120396 0.3048)
			(stroke
				(width 0.1)
				(type default)
			)
			(layer "F.Fab")
		)
		(pad "1" smd circle
			(at -0.40005 0)
			(size 0 0)
			(layers "F.Cu" "F.Mask" "F.Paste")
			(net "P3V3_AUX")
		)
		(pad "2" smd circle
			(at 0.40005 0)
			(size 0 0)
			(layers "F.Cu" "F.Mask" "F.Paste")
			(net "FAN_2_PWM")
		)
	)
	(footprint ""
		(layer "F.Cu")
		(at 14.351 -201.323956)
		(property "Reference" "R5225"
			(at 0 0 0)
			(layer "F.SilkS")
			(hide yes)
			(effects
				(font
					(size 1.27 1.27)
				)
			)
		)
		(property "Value" ""
			(at 0 0 0)
			(layer "F.Fab")
			(effects
				(font
					(size 1.27 1.27)
				)
			)
		)
		(duplicate_pad_numbers_are_jumpers no)
		(fp_line
			(start -0.7874 -0.4064)
			(end 0.7874 -0.4064)
			(stroke
				(width 0.1524)
				(type default)
			)
			(layer "F.SilkS")
		)
		(fp_line
			(start -0.7874 0.4064)
			(end -0.7874 -0.4064)
			(stroke
				(width 0.1524)
				(type default)
			)
			(layer "F.SilkS")
		)
		(fp_line
			(start 0.7874 -0.4064)
			(end 0.7874 0.4064)
			(stroke
				(width 0.1524)
				(type default)
			)
			(layer "F.SilkS")
		)
		(fp_line
			(start 0.7874 0.4064)
			(end -0.7874 0.4064)
			(stroke
				(width 0.1524)
				(type default)
			)
			(layer "F.SilkS")
		)
		(fp_line
			(start -0.67945 -0.305054)
			(end -0.12065 -0.305054)
			(stroke
				(width 0.1)
				(type default)
			)
			(layer "F.Fab")
		)
		(fp_line
			(start -0.67945 0.3048)
			(end -0.67945 -0.305054)
			(stroke
				(width 0.1)
				(type default)
			)
			(layer "F.Fab")
		)
		(fp_line
			(start -0.12065 -0.305054)
			(end -0.12065 -0.2794)
			(stroke
				(width 0.1)
				(type default)
			)
			(layer "F.Fab")
		)
		(fp_line
			(start -0.12065 -0.2794)
			(end 0.12065 -0.2794)
			(stroke
				(width 0.1)
				(type default)
			)
			(layer "F.Fab")
		)
		(fp_line
			(start -0.12065 0.2794)
			(end -0.12065 0.3048)
			(stroke
				(width 0.1)
				(type default)
			)
			(layer "F.Fab")
		)
		(fp_line
			(start -0.12065 0.3048)
			(end -0.67945 0.3048)
			(stroke
				(width 0.1)
				(type default)
			)
			(layer "F.Fab")
		)
		(fp_line
			(start 0.120396 0.2794)
			(end -0.12065 0.2794)
			(stroke
				(width 0.1)
				(type default)
			)
			(layer "F.Fab")
		)
		(fp_line
			(start 0.120396 0.3048)
			(end 0.120396 0.2794)
			(stroke
				(width 0.1)
				(type default)
			)
			(layer "F.Fab")
		)
		(fp_line
			(start 0.12065 -0.3048)
			(end 0.67945 -0.3048)
			(stroke
				(width 0.1)
				(type default)
			)
			(layer "F.Fab")
		)
		(fp_line
			(start 0.12065 -0.2794)
			(end 0.12065 -0.3048)
			(stroke
				(width 0.1)
				(type default)
			)
			(layer "F.Fab")
		)
		(fp_line
			(start 0.67945 -0.3048)
			(end 0.67945 0.3048)
			(stroke
				(width 0.1)
				(type default)
			)
			(layer "F.Fab")
		)
		(fp_line
			(start 0.67945 0.3048)
			(end 0.120396 0.3048)
			(stroke
				(width 0.1)
				(type default)
			)
			(layer "F.Fab")
		)
		(pad "1" smd circle
			(at -0.40005 0)
			(size 0 0)
			(layers "F.Cu" "F.Mask" "F.Paste")
			(net "SMB_FAN6_SDA_R")
		)
		(pad "2" smd circle
			(at 0.40005 0)
			(size 0 0)
			(layers "F.Cu" "F.Mask" "F.Paste")
			(net "SMB_FAN6_SDA")
		)
	)
	(footprint ""
		(layer "F.Cu")
		(at 30.353 -180.594)
		(property "Reference" "R510"
			(at 0 0 0)
			(layer "F.SilkS")
			(hide yes)
			(effects
				(font
					(size 1.27 1.27)
				)
			)
		)
		(property "Value" ""
			(at 0 0 0)
			(layer "F.Fab")
			(effects
				(font
					(size 1.27 1.27)
				)
			)
		)
		(duplicate_pad_numbers_are_jumpers no)
		(fp_line
			(start -0.7874 -0.4064)
			(end 0.7874 -0.4064)
			(stroke
				(width 0.1524)
				(type default)
			)
			(layer "F.SilkS")
		)
		(fp_line
			(start -0.7874 0.4064)
			(end -0.7874 -0.4064)
			(stroke
				(width 0.1524)
				(type default)
			)
			(layer "F.SilkS")
		)
		(fp_line
			(start 0.7874 -0.4064)
			(end 0.7874 0.4064)
			(stroke
				(width 0.1524)
				(type default)
			)
			(layer "F.SilkS")
		)
		(fp_line
			(start 0.7874 0.4064)
			(end -0.7874 0.4064)
			(stroke
				(width 0.1524)
				(type default)
			)
			(layer "F.SilkS")
		)
		(fp_line
			(start -0.67945 -0.305054)
			(end -0.12065 -0.305054)
			(stroke
				(width 0.1)
				(type default)
			)
			(layer "F.Fab")
		)
		(fp_line
			(start -0.67945 0.3048)
			(end -0.67945 -0.305054)
			(stroke
				(width 0.1)
				(type default)
			)
			(layer "F.Fab")
		)
		(fp_line
			(start -0.12065 -0.305054)
			(end -0.12065 -0.2794)
			(stroke
				(width 0.1)
				(type default)
			)
			(layer "F.Fab")
		)
		(fp_line
			(start -0.12065 -0.2794)
			(end 0.12065 -0.2794)
			(stroke
				(width 0.1)
				(type default)
			)
			(layer "F.Fab")
		)
		(fp_line
			(start -0.12065 0.2794)
			(end -0.12065 0.3048)
			(stroke
				(width 0.1)
				(type default)
			)
			(layer "F.Fab")
		)
		(fp_line
			(start -0.12065 0.3048)
			(end -0.67945 0.3048)
			(stroke
				(width 0.1)
				(type default)
			)
			(layer "F.Fab")
		)
		(fp_line
			(start 0.120396 0.2794)
			(end -0.12065 0.2794)
			(stroke
				(width 0.1)
				(type default)
			)
			(layer "F.Fab")
		)
		(fp_line
			(start 0.120396 0.3048)
			(end 0.120396 0.2794)
			(stroke
				(width 0.1)
				(type default)
			)
			(layer "F.Fab")
		)
		(fp_line
			(start 0.12065 -0.3048)
			(end 0.67945 -0.3048)
			(stroke
				(width 0.1)
				(type default)
			)
			(layer "F.Fab")
		)
		(fp_line
			(start 0.12065 -0.2794)
			(end 0.12065 -0.3048)
			(stroke
				(width 0.1)
				(type default)
			)
			(layer "F.Fab")
		)
		(fp_line
			(start 0.67945 -0.3048)
			(end 0.67945 0.3048)
			(stroke
				(width 0.1)
				(type default)
			)
			(layer "F.Fab")
		)
		(fp_line
			(start 0.67945 0.3048)
			(end 0.120396 0.3048)
			(stroke
				(width 0.1)
				(type default)
			)
			(layer "F.Fab")
		)
		(pad "1" smd circle
			(at -0.40005 0)
			(size 0 0)
			(layers "F.Cu" "F.Mask" "F.Paste")
			(net "P3V3_AUX")
		)
		(pad "2" smd circle
			(at 0.40005 0)
			(size 0 0)
			(layers "F.Cu" "F.Mask" "F.Paste")
			(net "P52V_FAN_1_BUFF_EN")
		)
	)
	(footprint ""
		(layer "F.Cu")
		(at 16.906494 -71.304912 -90)
		(property "Reference" "C2062"
			(at 0 0 270)
			(layer "F.SilkS")
			(hide yes)
			(effects
				(font
					(size 1.27 1.27)
				)
			)
		)
		(property "Value" ""
			(at 0 0 270)
			(layer "F.Fab")
			(effects
				(font
					(size 1.27 1.27)
				)
			)
		)
		(duplicate_pad_numbers_are_jumpers no)
		(fp_line
			(start -0.7874 0.4064)
			(end -0.7874 -0.4064)
			(stroke
				(width 0.1524)
				(type default)
			)
			(layer "F.SilkS")
		)
		(fp_line
			(start 0.7874 0.4064)
			(end -0.7874 0.4064)
			(stroke
				(width 0.1524)
				(type default)
			)
			(layer "F.SilkS")
		)
		(fp_line
			(start -0.7874 -0.4064)
			(end 0.7874 -0.4064)
			(stroke
				(width 0.1524)
				(type default)
			)
			(layer "F.SilkS")
		)
		(fp_line
			(start 0.7874 -0.4064)
			(end 0.7874 0.4064)
			(stroke
				(width 0.1524)
				(type default)
			)
			(layer "F.SilkS")
		)
		(fp_line
			(start -0.67945 0.3048)
			(end -0.67945 -0.305054)
			(stroke
				(width 0.1)
				(type default)
			)
			(layer "F.Fab")
		)
		(fp_line
			(start -0.12065 0.3048)
			(end -0.67945 0.3048)
			(stroke
				(width 0.1)
				(type default)
			)
			(layer "F.Fab")
		)
		(fp_line
			(start 0.120396 0.3048)
			(end 0.120396 0.2794)
			(stroke
				(width 0.1)
				(type default)
			)
			(layer "F.Fab")
		)
		(fp_line
			(start 0.67945 0.3048)
			(end 0.120396 0.3048)
			(stroke
				(width 0.1)
				(type default)
			)
			(layer "F.Fab")
		)
		(fp_line
			(start -0.12065 0.2794)
			(end -0.12065 0.3048)
			(stroke
				(width 0.1)
				(type default)
			)
			(layer "F.Fab")
		)
		(fp_line
			(start 0.120396 0.2794)
			(end -0.12065 0.2794)
			(stroke
				(width 0.1)
				(type default)
			)
			(layer "F.Fab")
		)
		(fp_line
			(start -0.12065 -0.2794)
			(end 0.12065 -0.2794)
			(stroke
				(width 0.1)
				(type default)
			)
			(layer "F.Fab")
		)
		(fp_line
			(start 0.12065 -0.2794)
			(end 0.12065 -0.3048)
			(stroke
				(width 0.1)
				(type default)
			)
			(layer "F.Fab")
		)
		(fp_line
			(start 0.12065 -0.3048)
			(end 0.67945 -0.3048)
			(stroke
				(width 0.1)
				(type default)
			)
			(layer "F.Fab")
		)
		(fp_line
			(start 0.67945 -0.3048)
			(end 0.67945 0.3048)
			(stroke
				(width 0.1)
				(type default)
			)
			(layer "F.Fab")
		)
		(fp_line
			(start -0.67945 -0.305054)
			(end -0.12065 -0.305054)
			(stroke
				(width 0.1)
				(type default)
			)
			(layer "F.Fab")
		)
		(fp_line
			(start -0.12065 -0.305054)
			(end -0.12065 -0.2794)
			(stroke
				(width 0.1)
				(type default)
			)
			(layer "F.Fab")
		)
		(pad "1" smd circle
			(at -0.40005 0 270)
			(size 0 0)
			(layers "F.Cu" "F.Mask" "F.Paste")
			(net "P3V3_AUX")
		)
		(pad "2" smd circle
			(at 0.40005 0 270)
			(size 0 0)
			(layers "F.Cu" "F.Mask" "F.Paste")
			(net "GND")
		)
	)
	(footprint ""
		(layer "F.Cu")
		(at 16.393922 -101.950012)
		(property "Reference" "C2032"
			(at 0 0 0)
			(layer "F.SilkS")
			(hide yes)
			(effects
				(font
					(size 1.27 1.27)
				)
			)
		)
		(property "Value" ""
			(at 0 0 0)
			(layer "F.Fab")
			(effects
				(font
					(size 1.27 1.27)
				)
			)
		)
		(duplicate_pad_numbers_are_jumpers no)
		(fp_line
			(start -0.7874 -0.4064)
			(end 0.7874 -0.4064)
			(stroke
				(width 0.1524)
				(type default)
			)
			(layer "F.SilkS")
		)
		(fp_line
			(start -0.7874 0.4064)
			(end -0.7874 -0.4064)
			(stroke
				(width 0.1524)
				(type default)
			)
			(layer "F.SilkS")
		)
		(fp_line
			(start 0.7874 -0.4064)
			(end 0.7874 0.4064)
			(stroke
				(width 0.1524)
				(type default)
			)
			(layer "F.SilkS")
		)
		(fp_line
			(start 0.7874 0.4064)
			(end -0.7874 0.4064)
			(stroke
				(width 0.1524)
				(type default)
			)
			(layer "F.SilkS")
		)
		(fp_line
			(start -0.67945 -0.305054)
			(end -0.12065 -0.305054)
			(stroke
				(width 0.1)
				(type default)
			)
			(layer "F.Fab")
		)
		(fp_line
			(start -0.67945 0.3048)
			(end -0.67945 -0.305054)
			(stroke
				(width 0.1)
				(type default)
			)
			(layer "F.Fab")
		)
		(fp_line
			(start -0.12065 -0.305054)
			(end -0.12065 -0.2794)
			(stroke
				(width 0.1)
				(type default)
			)
			(layer "F.Fab")
		)
		(fp_line
			(start -0.12065 -0.2794)
			(end 0.12065 -0.2794)
			(stroke
				(width 0.1)
				(type default)
			)
			(layer "F.Fab")
		)
		(fp_line
			(start -0.12065 0.2794)
			(end -0.12065 0.3048)
			(stroke
				(width 0.1)
				(type default)
			)
			(layer "F.Fab")
		)
		(fp_line
			(start -0.12065 0.3048)
			(end -0.67945 0.3048)
			(stroke
				(width 0.1)
				(type default)
			)
			(layer "F.Fab")
		)
		(fp_line
			(start 0.120396 0.2794)
			(end -0.12065 0.2794)
			(stroke
				(width 0.1)
				(type default)
			)
			(layer "F.Fab")
		)
		(fp_line
			(start 0.120396 0.3048)
			(end 0.120396 0.2794)
			(stroke
				(width 0.1)
				(type default)
			)
			(layer "F.Fab")
		)
		(fp_line
			(start 0.12065 -0.3048)
			(end 0.67945 -0.3048)
			(stroke
				(width 0.1)
				(type default)
			)
			(layer "F.Fab")
		)
		(fp_line
			(start 0.12065 -0.2794)
			(end 0.12065 -0.3048)
			(stroke
				(width 0.1)
				(type default)
			)
			(layer "F.Fab")
		)
		(fp_line
			(start 0.67945 -0.3048)
			(end 0.67945 0.3048)
			(stroke
				(width 0.1)
				(type default)
			)
			(layer "F.Fab")
		)
		(fp_line
			(start 0.67945 0.3048)
			(end 0.120396 0.3048)
			(stroke
				(width 0.1)
				(type default)
			)
			(layer "F.Fab")
		)
		(pad "1" smd circle
			(at -0.40005 0)
			(size 0 0)
			(layers "F.Cu" "F.Mask" "F.Paste")
			(net "FAN_5_PWM_OL_R")
		)
		(pad "2" smd circle
			(at 0.40005 0)
			(size 0 0)
			(layers "F.Cu" "F.Mask" "F.Paste")
			(net "GND")
		)
	)
)
